# T6G (Grand Teton) — schematic netlist excerpt (pin names and nets, part order shuffled) for the footprints in the layout excerpt that follows; sources: Cadence DE-HDL packaged netlist, KiCad conversion of 04192023_DAF0TMB3IC0_F0TG_MB_C_brd_V02_OCP.brd

R704  Q_RES  0 5% EMPTY  pkg 0402LF  page 334 : A = P1V8_CPU1_RT_1D ; B = P1V8_CPU1_RT1_1A_1D
R4062  Q_RES  0 5% CHIP  pkg 0402LF  page 152 : A = P12V_SCM_EN ; B = P12V_SCM_EN_R

(kicad_pcb
	(version 20260206)
	(generator "pcbnew")
	(generator_version "10.0")
	(general
		(thickness 1.6)
		(legacy_teardrops no)
	)
	(paper "A4")
	(title_block
		(title "04192023_DAF0TMB3IC0_F0TG_MB_C_brd_V02_OCP.brd")
		(comment 1 "Grand Teton / footprints 1976-1977 of 8354")
	)
	(layers
		(0 "F.Cu" signal "TOP")
		(4 "In1.Cu" signal "GND")
		(6 "In2.Cu" signal "IN1")
		(8 "In3.Cu" signal "GND1")
		(10 "In4.Cu" signal "IN2")
		(12 "In5.Cu" signal "GND2")
		(14 "In6.Cu" signal "IN3")
		(16 "In7.Cu" signal "GND3")
		(18 "In8.Cu" signal "VCC")
		(20 "In9.Cu" signal "VCC1")
		(22 "In10.Cu" signal "GND4")
		(24 "In11.Cu" signal "IN4")
		(26 "In12.Cu" signal "GND5")
		(28 "In13.Cu" signal "IN5")
		(30 "In14.Cu" signal "GND6")
		(32 "In15.Cu" signal "IN6")
		(34 "In16.Cu" signal "GND7")
		(2 "B.Cu" signal "BOTTOM")
		(9 "F.Adhes" user "F.Adhesive")
		(11 "B.Adhes" user "B.Adhesive")
		(13 "F.Paste" user "Package Geometry/Pastemask Top")
		(15 "B.Paste" user "Package Geometry/Pastemask Bottom")
		(5 "F.SilkS" user "Ref Des/Silkscreen Top")
		(7 "B.SilkS" user "Ref Des/Silkscreen Bottom")
		(1 "F.Mask" user "Board Geometry/Soldermask Top")
		(3 "B.Mask" user "Board Geometry/Soldermask Bottom")
		(17 "Dwgs.User" user "User.Drawings")
		(19 "Cmts.User" user "User.Comments")
		(21 "Eco1.User" user "User.Eco1")
		(23 "Eco2.User" user "User.Eco2")
		(25 "Edge.Cuts" user "Board Geometry/Outline")
		(27 "Margin" user)
		(31 "F.CrtYd" user "Package Geometry/Place Bound Top")
		(29 "B.CrtYd" user "Package Geometry/Place Bound Bottom")
		(35 "F.Fab" user "Ref Des/Assembly Top")
		(33 "B.Fab" user "Ref Des/Assembly Bottom")
	)
	(footprint ""
		(layer "F.Cu")
		(at 197.21068 -41.466516 180)
		(property "Reference" "R4062"
			(at 0 0 180)
			(layer "F.SilkS")
			(hide yes)
			(effects
				(font
					(size 1.27 1.27)
				)
			)
		)
		(property "Value" ""
			(at 0 0 180)
			(layer "F.Fab")
			(effects
				(font
					(size 1.27 1.27)
				)
			)
		)
		(duplicate_pad_numbers_are_jumpers no)
		(fp_line
			(start 0.7874 0.4064)
			(end -0.7874 0.4064)
			(stroke
				(width 0.1524)
				(type default)
			)
			(layer "F.SilkS")
		)
		(fp_line
			(start 0.7874 -0.4064)
			(end 0.7874 0.4064)
			(stroke
				(width 0.1524)
				(type default)
			)
			(layer "F.SilkS")
		)
		(fp_line
			(start -0.7874 0.4064)
			(end -0.7874 -0.4064)
			(stroke
				(width 0.1524)
				(type default)
			)
			(layer "F.SilkS")
		)
		(fp_line
			(start -0.7874 -0.4064)
			(end 0.7874 -0.4064)
			(stroke
				(width 0.1524)
				(type default)
			)
			(layer "F.SilkS")
		)
		(fp_line
			(start 0.67945 0.3048)
			(end 0.120396 0.3048)
			(stroke
				(width 0.1)
				(type default)
			)
			(layer "F.Fab")
		)
		(fp_line
			(start 0.67945 -0.3048)
			(end 0.67945 0.3048)
			(stroke
				(width 0.1)
				(type default)
			)
			(layer "F.Fab")
		)
		(fp_line
			(start 0.12065 -0.2794)
			(end 0.12065 -0.3048)
			(stroke
				(width 0.1)
				(type default)
			)
			(layer "F.Fab")
		)
		(fp_line
			(start 0.12065 -0.3048)
			(end 0.67945 -0.3048)
			(stroke
				(width 0.1)
				(type default)
			)
			(layer "F.Fab")
		)
		(fp_line
			(start 0.120396 0.3048)
			(end 0.120396 0.2794)
			(stroke
				(width 0.1)
				(type default)
			)
			(layer "F.Fab")
		)
		(fp_line
			(start 0.120396 0.2794)
			(end -0.12065 0.2794)
			(stroke
				(width 0.1)
				(type default)
			)
			(layer "F.Fab")
		)
		(fp_line
			(start -0.12065 0.3048)
			(end -0.67945 0.3048)
			(stroke
				(width 0.1)
				(type default)
			)
			(layer "F.Fab")
		)
		(fp_line
			(start -0.12065 0.2794)
			(end -0.12065 0.3048)
			(stroke
				(width 0.1)
				(type default)
			)
			(layer "F.Fab")
		)
		(fp_line
			(start -0.12065 -0.2794)
			(end 0.12065 -0.2794)
			(stroke
				(width 0.1)
				(type default)
			)
			(layer "F.Fab")
		)
		(fp_line
			(start -0.12065 -0.305054)
			(end -0.12065 -0.2794)
			(stroke
				(width 0.1)
				(type default)
			)
			(layer "F.Fab")
		)
		(fp_line
			(start -0.67945 0.3048)
			(end -0.67945 -0.305054)
			(stroke
				(width 0.1)
				(type default)
			)
			(layer "F.Fab")
		)
		(fp_line
			(start -0.67945 -0.305054)
			(end -0.12065 -0.305054)
			(stroke
				(width 0.1)
				(type default)
			)
			(layer "F.Fab")
		)
		(pad "1" smd circle
			(at -0.40005 0 180)
			(size 0 0)
			(layers "F.Cu" "F.Mask" "F.Paste")
			(net "P12V_SCM_EN")
		)
		(pad "2" smd circle
			(at 0.40005 0 180)
			(size 0 0)
			(layers "F.Cu" "F.Mask" "F.Paste")
			(net "P12V_SCM_EN_R")
		)
	)
	(footprint ""
		(layer "F.Cu")
		(at 103.190294 -384.10388 180)
		(property "Reference" "R704"
			(at 0 0 180)
			(layer "F.SilkS")
			(hide yes)
			(effects
				(font
					(size 1.27 1.27)
				)
			)
		)
		(property "Value" ""
			(at 0 0 180)
			(layer "F.Fab")
			(effects
				(font
					(size 1.27 1.27)
				)
			)
		)
		(duplicate_pad_numbers_are_jumpers no)
		(fp_line
			(start 0.7874 0.4064)
			(end -0.7874 0.4064)
			(stroke
				(width 0.1524)
				(type default)
			)
			(layer "F.SilkS")
		)
		(fp_line
			(start 0.7874 -0.4064)
			(end 0.7874 0.4064)
			(stroke
				(width 0.1524)
				(type default)
			)
			(layer "F.SilkS")
		)
		(fp_line
			(start -0.7874 0.4064)
			(end -0.7874 -0.4064)
			(stroke
				(width 0.1524)
				(type default)
			)
			(layer "F.SilkS")
		)
		(fp_line
			(start -0.7874 -0.4064)
			(end 0.7874 -0.4064)
			(stroke
				(width 0.1524)
				(type default)
			)
			(layer "F.SilkS")
		)
		(fp_line
			(start 0.67945 0.3048)
			(end 0.120396 0.3048)
			(stroke
				(width 0.1)
				(type default)
			)
			(layer "F.Fab")
		)
		(fp_line
			(start 0.67945 -0.3048)
			(end 0.67945 0.3048)
			(stroke
				(width 0.1)
				(type default)
			)
			(layer "F.Fab")
		)
		(fp_line
			(start 0.12065 -0.2794)
			(end 0.12065 -0.3048)
			(stroke
				(width 0.1)
				(type default)
			)
			(layer "F.Fab")
		)
		(fp_line
			(start 0.12065 -0.3048)
			(end 0.67945 -0.3048)
			(stroke
				(width 0.1)
				(type default)
			)
			(layer "F.Fab")
		)
		(fp_line
			(start 0.120396 0.3048)
			(end 0.120396 0.2794)
			(stroke
				(width 0.1)
				(type default)
			)
			(layer "F.Fab")
		)
		(fp_line
			(start 0.120396 0.2794)
			(end -0.12065 0.2794)
			(stroke
				(width 0.1)
				(type default)
			)
			(layer "F.Fab")
		)
		(fp_line
			(start -0.12065 0.3048)
			(end -0.67945 0.3048)
			(stroke
				(width 0.1)
				(type default)
			)
			(layer "F.Fab")
		)
		(fp_line
			(start -0.12065 0.2794)
			(end -0.12065 0.3048)
			(stroke
				(width 0.1)
				(type default)
			)
			(layer "F.Fab")
		)
		(fp_line
			(start -0.12065 -0.2794)
			(end 0.12065 -0.2794)
			(stroke
				(width 0.1)
				(type default)
			)
			(layer "F.Fab")
		)
		(fp_line
			(start -0.12065 -0.305054)
			(end -0.12065 -0.2794)
			(stroke
				(width 0.1)
				(type default)
			)
			(layer "F.Fab")
		)
		(fp_line
			(start -0.67945 0.3048)
			(end -0.67945 -0.305054)
			(stroke
				(width 0.1)
				(type default)
			)
			(layer "F.Fab")
		)
		(fp_line
			(start -0.67945 -0.305054)
			(end -0.12065 -0.305054)
			(stroke
				(width 0.1)
				(type default)
			)
			(layer "F.Fab")
		)
		(pad "1" smd rect
			(at -0.40005 0)
			(size 0.4572 0.508)
			(layers "F.Cu" "F.Mask" "F.Paste")
			(net "P1V8_CPU1_RT_1D")
		)
		(pad "2" smd rect
			(at 0.40005 0)
			(size 0.4572 0.508)
			(layers "F.Cu" "F.Mask" "F.Paste")
			(net "P1V8_CPU1_RT1_1A_1D")
		)
	)
)
